# T6G (Grand Teton) — schematic netlist excerpt (pin names and nets, part order shuffled) for the footprints in the layout excerpt that follows; sources: Cadence DE-HDL packaged netlist, KiCad conversion of 04192023_DAF0TMB3IC0_F0TG_MB_C_brd_V02_OCP.brd

C3920  Q_CAP  22UF 4V 20% X6S  pkg C0402  page 74 : A = PVDD11_S3_P1 ; B = GND
C18  Q_CAP  0.1UF 25V 10% X7R  pkg 0402  page 125 : A = SWB_HSC_PWRGD_ISO ; B = GND
R1061  Q_RES  10K 1% CHIP  pkg 0201LF  page 298 : A = RST_RT_CPU0_P2_PERST_R_N ; B = GND

(kicad_pcb
	(version 20260206)
	(generator "pcbnew")
	(generator_version "10.0")
	(general
		(thickness 1.6)
		(legacy_teardrops no)
	)
	(paper "A4")
	(title_block
		(title "04192023_DAF0TMB3IC0_F0TG_MB_C_brd_V02_OCP.brd")
		(comment 1 "Grand Teton / footprints 1858-1860 of 8354")
	)
	(layers
		(0 "F.Cu" signal "TOP")
		(4 "In1.Cu" signal "GND")
		(6 "In2.Cu" signal "IN1")
		(8 "In3.Cu" signal "GND1")
		(10 "In4.Cu" signal "IN2")
		(12 "In5.Cu" signal "GND2")
		(14 "In6.Cu" signal "IN3")
		(16 "In7.Cu" signal "GND3")
		(18 "In8.Cu" signal "VCC")
		(20 "In9.Cu" signal "VCC1")
		(22 "In10.Cu" signal "GND4")
		(24 "In11.Cu" signal "IN4")
		(26 "In12.Cu" signal "GND5")
		(28 "In13.Cu" signal "IN5")
		(30 "In14.Cu" signal "GND6")
		(32 "In15.Cu" signal "IN6")
		(34 "In16.Cu" signal "GND7")
		(2 "B.Cu" signal "BOTTOM")
		(9 "F.Adhes" user "F.Adhesive")
		(11 "B.Adhes" user "B.Adhesive")
		(13 "F.Paste" user "Package Geometry/Pastemask Top")
		(15 "B.Paste" user "Package Geometry/Pastemask Bottom")
		(5 "F.SilkS" user "Ref Des/Silkscreen Top")
		(7 "B.SilkS" user "Ref Des/Silkscreen Bottom")
		(1 "F.Mask" user "Board Geometry/Soldermask Top")
		(3 "B.Mask" user "Board Geometry/Soldermask Bottom")
		(17 "Dwgs.User" user "User.Drawings")
		(19 "Cmts.User" user "User.Comments")
		(21 "Eco1.User" user "User.Eco1")
		(23 "Eco2.User" user "User.Eco2")
		(25 "Edge.Cuts" user "Board Geometry/Outline")
		(27 "Margin" user)
		(31 "F.CrtYd" user "Package Geometry/Place Bound Top")
		(29 "B.CrtYd" user "Package Geometry/Place Bound Bottom")
		(35 "F.Fab" user "Ref Des/Assembly Top")
		(33 "B.Fab" user "Ref Des/Assembly Bottom")
	)
	(footprint ""
		(layer "F.Cu")
		(at 105.960164 -262.205216 180)
		(property "Reference" "C3920"
			(at 0 0 180)
			(layer "F.SilkS")
			(hide yes)
			(effects
				(font
					(size 1.27 1.27)
				)
			)
		)
		(property "Value" ""
			(at 0 0 180)
			(layer "F.Fab")
			(effects
				(font
					(size 1.27 1.27)
				)
			)
		)
		(duplicate_pad_numbers_are_jumpers no)
		(fp_line
			(start 0.7874 0.4064)
			(end -0.7874 0.4064)
			(stroke
				(width 0.1524)
				(type default)
			)
			(layer "F.SilkS")
		)
		(fp_line
			(start 0.7874 -0.4064)
			(end 0.7874 0.4064)
			(stroke
				(width 0.1524)
				(type default)
			)
			(layer "F.SilkS")
		)
		(fp_line
			(start -0.7874 0.4064)
			(end -0.7874 -0.4064)
			(stroke
				(width 0.1524)
				(type default)
			)
			(layer "F.SilkS")
		)
		(fp_line
			(start -0.7874 -0.4064)
			(end 0.7874 -0.4064)
			(stroke
				(width 0.1524)
				(type default)
			)
			(layer "F.SilkS")
		)
		(fp_line
			(start 0.67945 0.3048)
			(end 0.120396 0.3048)
			(stroke
				(width 0.1)
				(type default)
			)
			(layer "F.Fab")
		)
		(fp_line
			(start 0.67945 -0.3048)
			(end 0.67945 0.3048)
			(stroke
				(width 0.1)
				(type default)
			)
			(layer "F.Fab")
		)
		(fp_line
			(start 0.12065 -0.2794)
			(end 0.12065 -0.3048)
			(stroke
				(width 0.1)
				(type default)
			)
			(layer "F.Fab")
		)
		(fp_line
			(start 0.12065 -0.3048)
			(end 0.67945 -0.3048)
			(stroke
				(width 0.1)
				(type default)
			)
			(layer "F.Fab")
		)
		(fp_line
			(start 0.120396 0.3048)
			(end 0.120396 0.2794)
			(stroke
				(width 0.1)
				(type default)
			)
			(layer "F.Fab")
		)
		(fp_line
			(start 0.120396 0.2794)
			(end -0.12065 0.2794)
			(stroke
				(width 0.1)
				(type default)
			)
			(layer "F.Fab")
		)
		(fp_line
			(start -0.12065 0.3048)
			(end -0.67945 0.3048)
			(stroke
				(width 0.1)
				(type default)
			)
			(layer "F.Fab")
		)
		(fp_line
			(start -0.12065 0.2794)
			(end -0.12065 0.3048)
			(stroke
				(width 0.1)
				(type default)
			)
			(layer "F.Fab")
		)
		(fp_line
			(start -0.12065 -0.2794)
			(end 0.12065 -0.2794)
			(stroke
				(width 0.1)
				(type default)
			)
			(layer "F.Fab")
		)
		(fp_line
			(start -0.12065 -0.305054)
			(end -0.12065 -0.2794)
			(stroke
				(width 0.1)
				(type default)
			)
			(layer "F.Fab")
		)
		(fp_line
			(start -0.67945 0.3048)
			(end -0.67945 -0.305054)
			(stroke
				(width 0.1)
				(type default)
			)
			(layer "F.Fab")
		)
		(fp_line
			(start -0.67945 -0.305054)
			(end -0.12065 -0.305054)
			(stroke
				(width 0.1)
				(type default)
			)
			(layer "F.Fab")
		)
		(pad "1" smd circle
			(at -0.40005 0 180)
			(size 0 0)
			(layers "F.Cu" "F.Mask" "F.Paste")
			(net "PVDD11_S3_P1")
		)
		(pad "2" smd circle
			(at 0.40005 0 180)
			(size 0 0)
			(layers "F.Cu" "F.Mask" "F.Paste")
			(net "GND")
		)
	)
	(footprint ""
		(layer "F.Cu")
		(at 423.796206 -402.7424 -90)
		(property "Reference" "R1061"
			(at 0 0 270)
			(layer "F.SilkS")
			(hide yes)
			(effects
				(font
					(size 1.27 1.27)
				)
			)
		)
		(property "Value" ""
			(at 0 0 270)
			(layer "F.Fab")
			(effects
				(font
					(size 1.27 1.27)
				)
			)
		)
		(duplicate_pad_numbers_are_jumpers no)
		(fp_line
			(start -0.32512 0.175006)
			(end -0.32512 -0.175006)
			(stroke
				(width 0.1)
				(type default)
			)
			(layer "F.Fab")
		)
		(fp_line
			(start 0.32512 0.175006)
			(end -0.32512 0.175006)
			(stroke
				(width 0.1)
				(type default)
			)
			(layer "F.Fab")
		)
		(fp_line
			(start -0.32512 -0.175006)
			(end 0.32512 -0.175006)
			(stroke
				(width 0.1)
				(type default)
			)
			(layer "F.Fab")
		)
		(fp_line
			(start 0.32512 -0.175006)
			(end 0.32512 0.175006)
			(stroke
				(width 0.1)
				(type default)
			)
			(layer "F.Fab")
		)
		(pad "1" smd rect
			(at -0.2667 0 270)
			(size 0.3048 0.381)
			(layers "F.Cu" "F.Mask" "F.Paste")
			(net "RST_RT_CPU0_P2_PERST_R_N")
		)
		(pad "2" smd rect
			(at 0.2667 0 90)
			(size 0.3048 0.381)
			(layers "F.Cu" "F.Mask" "F.Paste")
			(net "GND")
		)
	)
	(footprint ""
		(layer "F.Cu")
		(at 353.185222 -424.279314)
		(property "Reference" "C18"
			(at 0 0 0)
			(layer "F.SilkS")
			(hide yes)
			(effects
				(font
					(size 1.27 1.27)
				)
			)
		)
		(property "Value" ""
			(at 0 0 0)
			(layer "F.Fab")
			(effects
				(font
					(size 1.27 1.27)
				)
			)
		)
		(duplicate_pad_numbers_are_jumpers no)
		(fp_line
			(start -0.7874 -0.4064)
			(end 0.7874 -0.4064)
			(stroke
				(width 0.1524)
				(type default)
			)
			(layer "F.SilkS")
		)
		(fp_line
			(start -0.7874 0.4064)
			(end -0.7874 -0.4064)
			(stroke
				(width 0.1524)
				(type default)
			)
			(layer "F.SilkS")
		)
		(fp_line
			(start 0.7874 -0.4064)
			(end 0.7874 0.4064)
			(stroke
				(width 0.1524)
				(type default)
			)
			(layer "F.SilkS")
		)
		(fp_line
			(start 0.7874 0.4064)
			(end -0.7874 0.4064)
			(stroke
				(width 0.1524)
				(type default)
			)
			(layer "F.SilkS")
		)
		(fp_line
			(start -0.67945 -0.305054)
			(end -0.12065 -0.305054)
			(stroke
				(width 0.1)
				(type default)
			)
			(layer "F.Fab")
		)
		(fp_line
			(start -0.67945 0.3048)
			(end -0.67945 -0.305054)
			(stroke
				(width 0.1)
				(type default)
			)
			(layer "F.Fab")
		)
		(fp_line
			(start -0.12065 -0.305054)
			(end -0.12065 -0.2794)
			(stroke
				(width 0.1)
				(type default)
			)
			(layer "F.Fab")
		)
		(fp_line
			(start -0.12065 -0.2794)
			(end 0.12065 -0.2794)
			(stroke
				(width 0.1)
				(type default)
			)
			(layer "F.Fab")
		)
		(fp_line
			(start -0.12065 0.2794)
			(end -0.12065 0.3048)
			(stroke
				(width 0.1)
				(type default)
			)
			(layer "F.Fab")
		)
		(fp_line
			(start -0.12065 0.3048)
			(end -0.67945 0.3048)
			(stroke
				(width 0.1)
				(type default)
			)
			(layer "F.Fab")
		)
		(fp_line
			(start 0.120396 0.2794)
			(end -0.12065 0.2794)
			(stroke
				(width 0.1)
				(type default)
			)
			(layer "F.Fab")
		)
		(fp_line
			(start 0.120396 0.3048)
			(end 0.120396 0.2794)
			(stroke
				(width 0.1)
				(type default)
			)
			(layer "F.Fab")
		)
		(fp_line
			(start 0.12065 -0.3048)
			(end 0.67945 -0.3048)
			(stroke
				(width 0.1)
				(type default)
			)
			(layer "F.Fab")
		)
		(fp_line
			(start 0.12065 -0.2794)
			(end 0.12065 -0.3048)
			(stroke
				(width 0.1)
				(type default)
			)
			(layer "F.Fab")
		)
		(fp_line
			(start 0.67945 -0.3048)
			(end 0.67945 0.3048)
			(stroke
				(width 0.1)
				(type default)
			)
			(layer "F.Fab")
		)
		(fp_line
			(start 0.67945 0.3048)
			(end 0.120396 0.3048)
			(stroke
				(width 0.1)
				(type default)
			)
			(layer "F.Fab")
		)
		(pad "1" smd circle
			(at -0.40005 0)
			(size 0 0)
			(layers "F.Cu" "F.Mask" "F.Paste")
			(net "SWB_HSC_PWRGD_ISO")
		)
		(pad "2" smd circle
			(at 0.40005 0)
			(size 0 0)
			(layers "F.Cu" "F.Mask" "F.Paste")
			(net "GND")
		)
	)
)
